Output: NC Drill Files
Type  : NC Drill
From  : Project [Timingcard_PROJECT.PrjPcb]
   Generated File[TimeCard-DC-V8_EXP-RoundHoles.TXT]
   Generated File[TimeCard-DC-V8_EXP-SlotHoles.TXT]
   Generated File[TimeCard-DC-V8_EXP.LDP]
   Generated File[TimeCard-DC-V8_EXP.DRR]


Files Generated   : 4
Documents Printed : 0

Finished Output Generation At 5:42:32 PM On 1/30/2023
